FILE_TYPE=LIBRARY_PARTS;
primitive 'RES_PWR','RES_PWR_4PAD';
  pin
    '1':
      PIN_NUMBER='(1)';
      PIN_TYPE='ANALOG';
      NO_LOAD_CHECK='BOTH';
      NO_IO_CHECK='BOTH';
      ALLOW_CONNECT='TRUE';
    '2':
      PIN_NUMBER='(2)';
      PIN_TYPE='ANALOG';
      NO_LOAD_CHECK='BOTH';
      NO_IO_CHECK='BOTH';
      ALLOW_CONNECT='TRUE';
    '3':
      PIN_NUMBER='(3)';
      PIN_TYPE='ANALOG';
      NO_LOAD_CHECK='BOTH';
      NO_IO_CHECK='BOTH';
      ALLOW_CONNECT='TRUE';
    '4':
      PIN_NUMBER='(4)';
      PIN_TYPE='ANALOG';
      NO_LOAD_CHECK='BOTH';
      NO_IO_CHECK='BOTH';
      ALLOW_CONNECT='TRUE';
  end_pin;
  body
    PART_NAME='RES_PWR';
    PHYS_DES_PREFIX='R';
end_body;
end_primitive;

primitive 'RES_PWR_6PAD';
  pin
    '1':
      PIN_NUMBER='(1)';
      PIN_TYPE='ANALOG';
      NO_LOAD_CHECK='Both';
      NO_IO_CHECK='Both';
      NO_ASSERT_CHECK='TRUE';
      NO_DIR_CHECK='TRUE';
      ALLOW_CONNECT='TRUE';
    '2':
      PIN_NUMBER='(2)';
      PIN_TYPE='ANALOG';
      NO_LOAD_CHECK='Both';
      NO_IO_CHECK='Both';
      NO_ASSERT_CHECK='TRUE';
      NO_DIR_CHECK='TRUE';
      ALLOW_CONNECT='TRUE';
    '3':
      PIN_NUMBER='(3)';
      PIN_TYPE='ANALOG';
      NO_LOAD_CHECK='Both';
      NO_IO_CHECK='Both';
      NO_ASSERT_CHECK='TRUE';
      NO_DIR_CHECK='TRUE';
      ALLOW_CONNECT='TRUE';
    '4':
      PIN_NUMBER='(4)';
      PIN_TYPE='ANALOG';
      NO_LOAD_CHECK='Both';
      NO_IO_CHECK='Both';
      NO_ASSERT_CHECK='TRUE';
      NO_DIR_CHECK='TRUE';
      ALLOW_CONNECT='TRUE';
    '5':
      PIN_NUMBER='(5)';
      PIN_TYPE='ANALOG';
      NO_LOAD_CHECK='Both';
      NO_IO_CHECK='Both';
      NO_ASSERT_CHECK='TRUE';
      NO_DIR_CHECK='TRUE';
      ALLOW_CONNECT='TRUE';
    '6':
      PIN_NUMBER='(6)';
      PIN_TYPE='ANALOG';
      NO_LOAD_CHECK='Both';
      NO_IO_CHECK='Both';
      NO_ASSERT_CHECK='TRUE';
      NO_DIR_CHECK='TRUE';
      ALLOW_CONNECT='TRUE';
  end_pin;
  body
    PART_NAME='RES_PWR';
    PHYS_DES_PREFIX='R';
end_body;
end_primitive;

END.
